# TIMECARD (Time Appliance Project (Time Card)) — schematic netlist excerpt (pin names and nets, part order shuffled) for the footprints in the layout excerpt that follows; sources: Cadence DE-HDL packaged netlist, KiCad conversion of R4006-B0001-02_R01.brd

C234  CAPACITOR  0.01UF 25V 10%  pkg SMC_0201R  page 31 : \1\ = UNNAMED_515_CAPACITOR_I138_1 ; \2\ = SG
TP78  TP_PIONT  pkg TP010CT020B030_PTH  page 25 : \1\ = IO_L20P_16
SP35  SOLDER_PREFORM  pkg 0201_SOLDER_PREFORM_4MIL  page 34 : \1\ = NC ; \2\ = NC

(kicad_pcb
	(version 20260206)
	(generator "pcbnew")
	(generator_version "10.0")
	(general
		(thickness 1.6)
		(legacy_teardrops no)
	)
	(paper "A4")
	(title_block
		(title "timecard-production-celestica-r4006 — R4006-B0001-02_R01.brd")
		(comment 1 "Time Appliance Project (Time Card) / footprints 658-660 of 1113")
	)
	(layers
		(0 "F.Cu" signal "TOP")
		(4 "In1.Cu" signal "L02_GND1")
		(6 "In2.Cu" signal "L03_SIG1")
		(8 "In3.Cu" signal "L04_GND2")
		(10 "In4.Cu" signal "L05_VCC1")
		(12 "In5.Cu" signal "L06_VCC2")
		(14 "In6.Cu" signal "L07_GND3")
		(16 "In7.Cu" signal "L08_SIG2")
		(18 "In8.Cu" signal "L09_GND4")
		(2 "B.Cu" signal "BOTTOM")
		(9 "F.Adhes" user "F.Adhesive")
		(11 "B.Adhes" user "B.Adhesive")
		(13 "F.Paste" user "Package Geometry/Pastemask Top")
		(15 "B.Paste" user "Package Geometry/Pastemask Bottom")
		(5 "F.SilkS" user "Ref Des/Silkscreen Top")
		(7 "B.SilkS" user "Ref Des/Silkscreen Bottom")
		(1 "F.Mask" user "Board Geometry/Soldermask Top")
		(3 "B.Mask" user "Board Geometry/Soldermask Bottom")
		(17 "Dwgs.User" user "User.Drawings")
		(19 "Cmts.User" user "User.Comments")
		(21 "Eco1.User" user "User.Eco1")
		(23 "Eco2.User" user "User.Eco2")
		(25 "Edge.Cuts" user "Board Geometry/Outline")
		(27 "Margin" user)
		(31 "F.CrtYd" user "Package Geometry/Place Bound Top")
		(29 "B.CrtYd" user "Package Geometry/Place Bound Bottom")
		(35 "F.Fab" user "Ref Des/Assembly Top")
		(33 "B.Fab" user "Ref Des/Assembly Bottom")
	)
	(footprint ""
		(layer "F.Cu")
		(at 138.43 -16.129 180)
		(property "Reference" "C234"
			(at 2.032 -1.56337 0)
			(unlocked yes)
			(layer "F.SilkS")
			(effects
				(font
					(size 0.7874 0.5842)
					(thickness 0.1524)
				)
			)
		)
		(property "Value" "VAL*"
			(at 0.193548 2.13614 180)
			(unlocked yes)
			(layer "F.Fab")
			(hide yes)
			(effects
				(font
					(size 0.7874 0.5842)
					(thickness 0.1524)
				)
			)
		)
		(property "User Part Number" "PARTNUM*"
			(at 0.216154 4.185666 180)
			(unlocked yes)
			(layer "Cmts.User")
			(hide yes)
			(effects
				(font
					(size 0.7874 0.5842)
					(thickness 0.1524)
				)
			)
		)
		(property "Device Type" "CAPACITOR-G104-0B103-EK,0.01UFA"
			(at 0.184404 1.180592 180)
			(unlocked yes)
			(layer "F.Fab")
			(hide yes)
			(effects
				(font
					(size 0.7874 0.5842)
					(thickness 0.1524)
				)
			)
		)
		(property "Tolerance" "TOL*"
			(at 0.216154 3.1496 180)
			(unlocked yes)
			(layer "Cmts.User")
			(hide yes)
			(effects
				(font
					(size 0.7874 0.5842)
					(thickness 0.1524)
				)
			)
		)
		(duplicate_pad_numbers_are_jumpers no)
		(fp_line
			(start 0.671322 0.4445)
			(end -0.671322 0.4445)
			(stroke
				(width 0.1)
				(type default)
			)
			(layer "F.SilkS")
		)
		(fp_line
			(start 0.671322 -0.4445)
			(end 0.671322 0.4445)
			(stroke
				(width 0.1)
				(type default)
			)
			(layer "F.SilkS")
		)
		(fp_line
			(start -0.671322 0.4445)
			(end -0.671322 -0.4445)
			(stroke
				(width 0.1)
				(type default)
			)
			(layer "F.SilkS")
		)
		(fp_line
			(start -0.671322 -0.4445)
			(end 0.671322 -0.4445)
			(stroke
				(width 0.1)
				(type default)
			)
			(layer "F.SilkS")
		)
		(fp_rect
			(start -0.671322 -0.4445)
			(end 0.671322 0.4445)
			(stroke
				(width 0)
				(type default)
			)
			(fill no)
			(layer "F.CrtYd")
		)
		(fp_line
			(start 0.31496 0.1651)
			(end 0.31496 -0.1651)
			(stroke
				(width 0.1)
				(type default)
			)
			(layer "F.Fab")
		)
		(fp_line
			(start 0.31496 -0.1651)
			(end -0.31496 -0.1651)
			(stroke
				(width 0.1)
				(type default)
			)
			(layer "F.Fab")
		)
		(fp_line
			(start -0.31496 0.1651)
			(end 0.31496 0.1651)
			(stroke
				(width 0.1)
				(type default)
			)
			(layer "F.Fab")
		)
		(fp_line
			(start -0.31496 -0.1651)
			(end -0.31496 0.1651)
			(stroke
				(width 0.1)
				(type default)
			)
			(layer "F.Fab")
		)
		(pad "1" smd rect
			(at -0.264922 0 180)
			(size 0.3048 0.381)
			(layers "F.Cu" "F.Mask" "F.Paste")
			(net "UNNAMED_515_CAPACITOR_I138_1")
		)
		(pad "2" smd rect
			(at 0.264922 0 180)
			(size 0.3048 0.381)
			(layers "F.Cu" "F.Mask" "F.Paste")
			(net "SG")
		)
		(zone
			(layer "F.Cu")
			(hatch none 0.5)
			(connect_pads
				(clearance 0)
			)
			(min_thickness 0.25)
			(keepout
				(tracks allowed)
				(vias not_allowed)
				(pads allowed)
				(copperpour not_allowed)
				(footprints allowed)
			)
			(placement
				(enabled no)
				(sheetname "")
			)
			(fill
				(thermal_gap 0.5)
				(thermal_bridge_width 0.5)
				(island_removal_mode 0)
			)
			(polygon
				(pts
					(xy 138.542522 -15.9385) (xy 138.542522 -16.3195) (xy 138.317478 -16.3195) (xy 138.317478 -15.9385)
				)
			)
		)
	)
	(footprint ""
		(layer "F.Cu")
		(at 99.06 -59.055 90)
		(property "Reference" "TP78"
			(at -2.9464 -0.47625 90)
			(unlocked yes)
			(layer "F.SilkS")
			(effects
				(font
					(size 0.635 0.4064)
					(thickness 0.1524)
				)
				(justify left)
			)
		)
		(property "Value" ""
			(at 0 0 90)
			(layer "F.Fab")
			(effects
				(font
					(size 1.27 1.27)
				)
			)
		)
		(property "Device Type" "TP_PIONT-TP010CT020B030_PTH-TPA"
			(at -1.341882 0.996696 90)
			(unlocked yes)
			(layer "F.Fab")
			(hide yes)
			(effects
				(font
					(size 0.7874 0.5842)
					(thickness 0.1524)
				)
				(justify left)
			)
		)
		(duplicate_pad_numbers_are_jumpers no)
		(fp_poly
			(pts
				(arc
					(start 0 0.889)
					(mid 0 -0.889)
					(end 0 0.889)
				)
			)
			(stroke
				(width 0)
				(type default)
			)
			(fill no)
			(layer "B.CrtYd")
		)
		(fp_poly
			(pts
				(arc
					(start 0 0.889)
					(mid 0 -0.889)
					(end 0 0.889)
				)
			)
			(stroke
				(width 0)
				(type default)
			)
			(fill no)
			(layer "F.CrtYd")
		)
		(pad "1" thru_hole circle
			(at 0 0 90)
			(size 0.508 0.508)
			(drill 0.254)
			(layers "*.Cu" "*.Mask")
			(remove_unused_layers no)
			(net "IO_L20P_16")
			(clearance 0.1016)
			(padstack
				(mode front_inner_back)
				(layer "Inner"
					(shape circle)
					(size 0.508 0.508)
					(clearance 0.1016)
				)
				(layer "B.Cu"
					(shape circle)
					(size 0.762 0.762)
					(clearance -0.0254)
				)
			)
		)
	)
	(footprint ""
		(layer "F.Cu")
		(at 39.37 -128.905)
		(property "Reference" "SP35"
			(at 0 0 0)
			(layer "F.SilkS")
			(hide yes)
			(effects
				(font
					(size 1.27 1.27)
				)
			)
		)
		(property "Value" ""
			(at 0 0 0)
			(layer "F.Fab")
			(effects
				(font
					(size 1.27 1.27)
				)
			)
		)
		(duplicate_pad_numbers_are_jumpers no)
	)
)
